(kicad_pcb
	(version 20221018)
	(generator pcbnew)
	(general
    (thickness 1.586)
  )
	(paper "A4")
	(title_block
    (date "2024-03-26")
    (rev "1.1.3")
		(comment 9 "footprint 11 of 146 (J8), pads 1-100 of 100")
	)
	(layers
    (0 "F.Cu" signal)
    (1 "In1.Cu" power)
    (2 "In2.Cu" power)
    (31 "B.Cu" signal)
    (32 "B.Adhes" user "B.Adhesive")
    (33 "F.Adhes" user "F.Adhesive")
    (34 "B.Paste" user)
    (35 "F.Paste" user)
    (36 "B.SilkS" user "B.Silkscreen")
    (37 "F.SilkS" user "F.Silkscreen")
    (38 "B.Mask" user)
    (39 "F.Mask" user)
    (40 "Dwgs.User" user "User.Drawings")
    (41 "Cmts.User" user "User.Comments")
    (42 "Eco1.User" user "User.Eco1")
    (43 "Eco2.User" user "User.Eco2")
    (44 "Edge.Cuts" user)
    (45 "Margin" user)
    (46 "B.CrtYd" user "B.Courtyard")
    (47 "F.CrtYd" user "F.Courtyard")
    (48 "B.Fab" user)
    (49 "F.Fab" user)
  )
	(footprint "scalenode-cm4-baseboard-footprints:Conn_Socket_Hirose_DF40_2x50_DF40HC-3.0-100DS-0.4V"
    (layer "F.Cu")
    (at 167.17772 93.80168 180)
    (property "Author" "Antmicro")
    (property "License" "Apache-2.0")
    (property "MPN" "DF40HC(3.0)-100DS-0.4V(51)")
    (property "Manufacturer" "Hirose Electric")
    (property "Pitch" "0.4 mm")
    (property "Sheetfile" "compute-module.kicad_sch")
    (property "Sheetname" "Compute module")
    (property "ki_description" "100 Position Connector Receptacle, Center Strip Contacts Surface Mount Gold")
    (property "ki_keywords" "CONNECTOR, B2B, SOCKET")
    (attr smd)
    (fp_text reference "J8" (at -12.87 0.119) (layer "F.SilkS")
        (effects (font (size 0.7 0.7) (thickness 0.15)) (justify left bottom))
    )
    (fp_text value "Socket_Hirose_DF40_2x50_DF40HC-3.0-100DS-0.4V" (at 0.109 2.999) (layer "F.Fab")
        (effects (font (size 0.7 0.7) (thickness 0.15)) (justify left bottom))
    )
    (pad "1" smd rect (at -9.801 1.54 180) (size 0.2 0.7) (layers "F.Cu" "F.Paste" "F.Mask")
      (net 95 "USBOTG_ID") (pintype "passive"))
    (pad "2" smd rect (at -9.801 -1.541 180) (size 0.2 0.7) (layers "F.Cu" "F.Paste" "F.Mask")
      (net 96 "PCIE_CLK_nREQ") (pintype "passive"))
    (pad "3" smd rect (at -9.401 1.54 180) (size 0.2 0.7) (layers "F.Cu" "F.Paste" "F.Mask")
      (net 97 "USB2_N") (pintype "passive"))
    (pad "4" smd rect (at -9.401 -1.541 180) (size 0.2 0.7) (layers "F.Cu" "F.Paste" "F.Mask")
      (net 209 "unconnected-(J8-Pad4)") (pintype "passive+no_connect"))
    (pad "5" smd rect (at -9 1.54 180) (size 0.2 0.7) (layers "F.Cu" "F.Paste" "F.Mask")
      (net 98 "USB2_P") (pintype "passive"))
    (pad "6" smd rect (at -9 -1.541 180) (size 0.2 0.7) (layers "F.Cu" "F.Paste" "F.Mask")
      (net 210 "unconnected-(J8-Pad6)") (pintype "passive+no_connect"))
    (pad "7" smd rect (at -8.6 1.54 180) (size 0.2 0.7) (layers "F.Cu" "F.Paste" "F.Mask")
      (net 11 "GND") (pintype "passive"))
    (pad "8" smd rect (at -8.6 -1.541 180) (size 0.2 0.7) (layers "F.Cu" "F.Paste" "F.Mask")
      (net 11 "GND") (pintype "passive"))
    (pad "9" smd rect (at -8.2 1.54 180) (size 0.2 0.7) (layers "F.Cu" "F.Paste" "F.Mask")
      (net 99 "PSCIE_nRST") (pintype "passive"))
    (pad "10" smd rect (at -8.2 -1.541 180) (size 0.2 0.7) (layers "F.Cu" "F.Paste" "F.Mask")
      (net 100 "PCIE_CLK_P") (pintype "passive"))
    (pad "11" smd rect (at -7.8 1.54 180) (size 0.2 0.7) (layers "F.Cu" "F.Paste" "F.Mask")
      (net 101 "TV_OUT") (pintype "passive"))
    (pad "12" smd rect (at -7.8 -1.541 180) (size 0.2 0.7) (layers "F.Cu" "F.Paste" "F.Mask")
      (net 102 "PCIE_CLK_N") (pintype "passive"))
    (pad "13" smd rect (at -7.401 1.54 180) (size 0.2 0.7) (layers "F.Cu" "F.Paste" "F.Mask")
      (net 11 "GND") (pintype "passive"))
    (pad "14" smd rect (at -7.401 -1.541 180) (size 0.2 0.7) (layers "F.Cu" "F.Paste" "F.Mask")
      (net 11 "GND") (pintype "passive"))
    (pad "15" smd rect (at -7 1.54 180) (size 0.2 0.7) (layers "F.Cu" "F.Paste" "F.Mask")
      (net 103 "CAM1_D0_N") (pintype "passive"))
    (pad "16" smd rect (at -7 -1.541 180) (size 0.2 0.7) (layers "F.Cu" "F.Paste" "F.Mask")
      (net 18 "PCIE_RX_P") (pintype "passive"))
    (pad "17" smd rect (at -6.6 1.54 180) (size 0.2 0.7) (layers "F.Cu" "F.Paste" "F.Mask")
      (net 104 "CAM1_D0_P") (pintype "passive"))
    (pad "18" smd rect (at -6.6 -1.541 180) (size 0.2 0.7) (layers "F.Cu" "F.Paste" "F.Mask")
      (net 16 "PCIE_RX_N") (pintype "passive"))
    (pad "19" smd rect (at -6.201 1.54 180) (size 0.2 0.7) (layers "F.Cu" "F.Paste" "F.Mask")
      (net 11 "GND") (pintype "passive"))
    (pad "20" smd rect (at -6.201 -1.541 180) (size 0.2 0.7) (layers "F.Cu" "F.Paste" "F.Mask")
      (net 11 "GND") (pintype "passive"))
    (pad "21" smd rect (at -5.8 1.54 180) (size 0.2 0.7) (layers "F.Cu" "F.Paste" "F.Mask")
      (net 105 "CAM1_D1_N") (pintype "passive"))
    (pad "22" smd rect (at -5.8 -1.541 180) (size 0.2 0.7) (layers "F.Cu" "F.Paste" "F.Mask")
      (net 17 "PCIE_TX_P") (pintype "passive"))
    (pad "23" smd rect (at -5.401 1.54 180) (size 0.2 0.7) (layers "F.Cu" "F.Paste" "F.Mask")
      (net 106 "CAM1_D1_P") (pintype "passive"))
    (pad "24" smd rect (at -5.401 -1.541 180) (size 0.2 0.7) (layers "F.Cu" "F.Paste" "F.Mask")
      (net 15 "PCIE_TX_N") (pintype "passive"))
    (pad "25" smd rect (at -5 1.54 180) (size 0.2 0.7) (layers "F.Cu" "F.Paste" "F.Mask")
      (net 11 "GND") (pintype "passive"))
    (pad "26" smd rect (at -5 -1.541 180) (size 0.2 0.7) (layers "F.Cu" "F.Paste" "F.Mask")
      (net 11 "GND") (pintype "passive"))
    (pad "27" smd rect (at -4.6 1.54 180) (size 0.2 0.7) (layers "F.Cu" "F.Paste" "F.Mask")
      (net 107 "CAM1_C_N") (pintype "passive"))
    (pad "28" smd rect (at -4.6 -1.541 180) (size 0.2 0.7) (layers "F.Cu" "F.Paste" "F.Mask")
      (net 108 "CAM0_D0_N") (pintype "passive"))
    (pad "29" smd rect (at -4.201 1.54 180) (size 0.2 0.7) (layers "F.Cu" "F.Paste" "F.Mask")
      (net 109 "CAM1_C_P") (pintype "passive"))
    (pad "30" smd rect (at -4.201 -1.541 180) (size 0.2 0.7) (layers "F.Cu" "F.Paste" "F.Mask")
      (net 110 "CAM0_D0_P") (pintype "passive"))
    (pad "31" smd rect (at -3.8 1.54 180) (size 0.2 0.7) (layers "F.Cu" "F.Paste" "F.Mask")
      (net 11 "GND") (pintype "passive"))
    (pad "32" smd rect (at -3.8 -1.541 180) (size 0.2 0.7) (layers "F.Cu" "F.Paste" "F.Mask")
      (net 11 "GND") (pintype "passive"))
    (pad "33" smd rect (at -3.4 1.54 180) (size 0.2 0.7) (layers "F.Cu" "F.Paste" "F.Mask")
      (net 111 "CAM1_D2_N") (pintype "passive"))
    (pad "34" smd rect (at -3.4 -1.541 180) (size 0.2 0.7) (layers "F.Cu" "F.Paste" "F.Mask")
      (net 112 "CAM0_D1_N") (pintype "passive"))
    (pad "35" smd rect (at -3 1.54 180) (size 0.2 0.7) (layers "F.Cu" "F.Paste" "F.Mask")
      (net 113 "CAM1_D2_P") (pintype "passive"))
    (pad "36" smd rect (at -3 -1.541 180) (size 0.2 0.7) (layers "F.Cu" "F.Paste" "F.Mask")
      (net 114 "CAM0_D1_P") (pintype "passive"))
    (pad "37" smd rect (at -2.601 1.54 180) (size 0.2 0.7) (layers "F.Cu" "F.Paste" "F.Mask")
      (net 11 "GND") (pintype "passive"))
    (pad "38" smd rect (at -2.601 -1.541 180) (size 0.2 0.7) (layers "F.Cu" "F.Paste" "F.Mask")
      (net 11 "GND") (pintype "passive"))
    (pad "39" smd rect (at -2.201 1.54 180) (size 0.2 0.7) (layers "F.Cu" "F.Paste" "F.Mask")
      (net 115 "CAM1_D3_N") (pintype "passive"))
    (pad "40" smd rect (at -2.201 -1.541 180) (size 0.2 0.7) (layers "F.Cu" "F.Paste" "F.Mask")
      (net 116 "CAM0_C_N") (pintype "passive"))
    (pad "41" smd rect (at -1.801 1.54 180) (size 0.2 0.7) (layers "F.Cu" "F.Paste" "F.Mask")
      (net 117 "CAM1_D3_P") (pintype "passive"))
    (pad "42" smd rect (at -1.801 -1.541 180) (size 0.2 0.7) (layers "F.Cu" "F.Paste" "F.Mask")
      (net 118 "CAM0_C_P") (pintype "passive"))
    (pad "43" smd rect (at -1.4 1.54 180) (size 0.2 0.7) (layers "F.Cu" "F.Paste" "F.Mask")
      (net 119 "HDMI1_HOTPLUG") (pintype "passive"))
    (pad "44" smd rect (at -1.4 -1.541 180) (size 0.2 0.7) (layers "F.Cu" "F.Paste" "F.Mask")
      (net 11 "GND") (pintype "passive"))
    (pad "45" smd rect (at -1 1.54 180) (size 0.2 0.7) (layers "F.Cu" "F.Paste" "F.Mask")
      (net 120 "HDMI1_SDA") (pintype "passive"))
    (pad "46" smd rect (at -1 -1.541 180) (size 0.2 0.7) (layers "F.Cu" "F.Paste" "F.Mask")
      (net 121 "HDMI1_D2_P") (pintype "passive"))
    (pad "47" smd rect (at -0.6 1.54 180) (size 0.2 0.7) (layers "F.Cu" "F.Paste" "F.Mask")
      (net 122 "HDMI1_SCL") (pintype "passive"))
    (pad "48" smd rect (at -0.6 -1.541 180) (size 0.2 0.7) (layers "F.Cu" "F.Paste" "F.Mask")
      (net 123 "HDMI1_D2_N") (pintype "passive"))
    (pad "49" smd rect (at -0.201 1.54 180) (size 0.2 0.7) (layers "F.Cu" "F.Paste" "F.Mask")
      (net 124 "HDMI1_CEC") (pintype "passive"))
    (pad "50" smd rect (at -0.201 -1.541 180) (size 0.2 0.7) (layers "F.Cu" "F.Paste" "F.Mask")
      (net 11 "GND") (pintype "passive"))
    (pad "51" smd rect (at 0.2 1.54 180) (size 0.2 0.7) (layers "F.Cu" "F.Paste" "F.Mask")
      (net 125 "HDMI0_CEC") (pintype "passive"))
    (pad "52" smd rect (at 0.2 -1.541 180) (size 0.2 0.7) (layers "F.Cu" "F.Paste" "F.Mask")
      (net 126 "HDMI1_D1_P") (pintype "passive"))
    (pad "53" smd rect (at 0.599 1.54 180) (size 0.2 0.7) (layers "F.Cu" "F.Paste" "F.Mask")
      (net 127 "HDMI0_HOTPLUG") (pintype "passive"))
    (pad "54" smd rect (at 0.599 -1.541 180) (size 0.2 0.7) (layers "F.Cu" "F.Paste" "F.Mask")
      (net 128 "HDMI1_D1_N") (pintype "passive"))
    (pad "55" smd rect (at 0.999 1.54 180) (size 0.2 0.7) (layers "F.Cu" "F.Paste" "F.Mask")
      (net 11 "GND") (pintype "passive"))
    (pad "56" smd rect (at 0.999 -1.541 180) (size 0.2 0.7) (layers "F.Cu" "F.Paste" "F.Mask")
      (net 11 "GND") (pintype "passive"))
    (pad "57" smd rect (at 1.399 1.54 180) (size 0.2 0.7) (layers "F.Cu" "F.Paste" "F.Mask")
      (net 129 "DSI0_D0_N") (pintype "passive"))
    (pad "58" smd rect (at 1.399 -1.541 180) (size 0.2 0.7) (layers "F.Cu" "F.Paste" "F.Mask")
      (net 130 "HDMI1_D0_P") (pintype "passive"))
    (pad "59" smd rect (at 1.8 1.54 180) (size 0.2 0.7) (layers "F.Cu" "F.Paste" "F.Mask")
      (net 131 "DSI0_D0_P") (pintype "passive"))
    (pad "60" smd rect (at 1.8 -1.541 180) (size 0.2 0.7) (layers "F.Cu" "F.Paste" "F.Mask")
      (net 132 "HDMI1_D0_N") (pintype "passive"))
    (pad "61" smd rect (at 2.2 1.54 180) (size 0.2 0.7) (layers "F.Cu" "F.Paste" "F.Mask")
      (net 11 "GND") (pintype "passive"))
    (pad "62" smd rect (at 2.2 -1.541 180) (size 0.2 0.7) (layers "F.Cu" "F.Paste" "F.Mask")
      (net 11 "GND") (pintype "passive"))
    (pad "63" smd rect (at 2.6 1.54 180) (size 0.2 0.7) (layers "F.Cu" "F.Paste" "F.Mask")
      (net 133 "DSI0_D1_N") (pintype "passive"))
    (pad "64" smd rect (at 2.6 -1.541 180) (size 0.2 0.7) (layers "F.Cu" "F.Paste" "F.Mask")
      (net 134 "HDMI1_CK_P") (pintype "passive"))
    (pad "65" smd rect (at 2.999 1.54 180) (size 0.2 0.7) (layers "F.Cu" "F.Paste" "F.Mask")
      (net 135 "DSI0_D1_P") (pintype "passive"))
    (pad "66" smd rect (at 2.999 -1.541 180) (size 0.2 0.7) (layers "F.Cu" "F.Paste" "F.Mask")
      (net 136 "HDMI1_CK_N") (pintype "passive"))
    (pad "67" smd rect (at 3.399 1.54 180) (size 0.2 0.7) (layers "F.Cu" "F.Paste" "F.Mask")
      (net 11 "GND") (pintype "passive"))
    (pad "68" smd rect (at 3.399 -1.541 180) (size 0.2 0.7) (layers "F.Cu" "F.Paste" "F.Mask")
      (net 11 "GND") (pintype "passive"))
    (pad "69" smd rect (at 3.799 1.54 180) (size 0.2 0.7) (layers "F.Cu" "F.Paste" "F.Mask")
      (net 137 "DSI0_C_N") (pintype "passive"))
    (pad "70" smd rect (at 3.799 -1.541 180) (size 0.2 0.7) (layers "F.Cu" "F.Paste" "F.Mask")
      (net 36 "HDMI0_D2_P") (pintype "passive"))
    (pad "71" smd rect (at 4.2 1.54 180) (size 0.2 0.7) (layers "F.Cu" "F.Paste" "F.Mask")
      (net 138 "DSI0_C_P") (pintype "passive"))
    (pad "72" smd rect (at 4.2 -1.541 180) (size 0.2 0.7) (layers "F.Cu" "F.Paste" "F.Mask")
      (net 37 "HDMI0_D2_N") (pintype "passive"))
    (pad "73" smd rect (at 4.599 1.54 180) (size 0.2 0.7) (layers "F.Cu" "F.Paste" "F.Mask")
      (net 11 "GND") (pintype "passive"))
    (pad "74" smd rect (at 4.599 -1.541 180) (size 0.2 0.7) (layers "F.Cu" "F.Paste" "F.Mask")
      (net 11 "GND") (pintype "passive"))
    (pad "75" smd rect (at 4.999 1.54 180) (size 0.2 0.7) (layers "F.Cu" "F.Paste" "F.Mask")
      (net 139 "DSI1_D0_N") (pintype "passive"))
    (pad "76" smd rect (at 4.999 -1.541 180) (size 0.2 0.7) (layers "F.Cu" "F.Paste" "F.Mask")
      (net 38 "HDMI0_D1_P") (pintype "passive"))
    (pad "77" smd rect (at 5.4 1.54 180) (size 0.2 0.7) (layers "F.Cu" "F.Paste" "F.Mask")
      (net 140 "DSI1_D0_P") (pintype "passive"))
    (pad "78" smd rect (at 5.4 -1.541 180) (size 0.2 0.7) (layers "F.Cu" "F.Paste" "F.Mask")
      (net 39 "HDMI0_D1_N") (pintype "passive"))
    (pad "79" smd rect (at 5.799 1.54 180) (size 0.2 0.7) (layers "F.Cu" "F.Paste" "F.Mask")
      (net 11 "GND") (pintype "passive"))
    (pad "80" smd rect (at 5.799 -1.541 180) (size 0.2 0.7) (layers "F.Cu" "F.Paste" "F.Mask")
      (net 11 "GND") (pintype "passive"))
    (pad "81" smd rect (at 6.2 1.54 180) (size 0.2 0.7) (layers "F.Cu" "F.Paste" "F.Mask")
      (net 141 "DSI1_D1_N") (pintype "passive"))
    (pad "82" smd rect (at 6.2 -1.541 180) (size 0.2 0.7) (layers "F.Cu" "F.Paste" "F.Mask")
      (net 142 "HDMI0_D0_P") (pintype "passive"))
    (pad "83" smd rect (at 6.599 1.54 180) (size 0.2 0.7) (layers "F.Cu" "F.Paste" "F.Mask")
      (net 143 "DSI1_D1_P") (pintype "passive"))
    (pad "84" smd rect (at 6.599 -1.541 180) (size 0.2 0.7) (layers "F.Cu" "F.Paste" "F.Mask")
      (net 144 "HDMI0_D0_N") (pintype "passive"))
    (pad "85" smd rect (at 6.999 1.54 180) (size 0.2 0.7) (layers "F.Cu" "F.Paste" "F.Mask")
      (net 11 "GND") (pintype "passive"))
    (pad "86" smd rect (at 6.999 -1.541 180) (size 0.2 0.7) (layers "F.Cu" "F.Paste" "F.Mask")
      (net 11 "GND") (pintype "passive"))
    (pad "87" smd rect (at 7.4 1.54 180) (size 0.2 0.7) (layers "F.Cu" "F.Paste" "F.Mask")
      (net 145 "DSI1_C_N") (pintype "passive"))
    (pad "88" smd rect (at 7.4 -1.541 180) (size 0.2 0.7) (layers "F.Cu" "F.Paste" "F.Mask")
      (net 40 "HDMI0_CK_P") (pintype "passive"))
    (pad "89" smd rect (at 7.799 1.54 180) (size 0.2 0.7) (layers "F.Cu" "F.Paste" "F.Mask")
      (net 146 "DSI1_C_P") (pintype "passive"))
    (pad "90" smd rect (at 7.799 -1.541 180) (size 0.2 0.7) (layers "F.Cu" "F.Paste" "F.Mask")
      (net 41 "HDMI0_CK_N") (pintype "passive"))
    (pad "91" smd rect (at 8.199 1.54 180) (size 0.2 0.7) (layers "F.Cu" "F.Paste" "F.Mask")
      (net 11 "GND") (pintype "passive"))
    (pad "92" smd rect (at 8.199 -1.541 180) (size 0.2 0.7) (layers "F.Cu" "F.Paste" "F.Mask")
      (net 11 "GND") (pintype "passive"))
    (pad "93" smd rect (at 8.599 1.54 180) (size 0.2 0.7) (layers "F.Cu" "F.Paste" "F.Mask")
      (net 147 "DSI2_D1_N") (pintype "passive"))
    (pad "94" smd rect (at 8.599 -1.541 180) (size 0.2 0.7) (layers "F.Cu" "F.Paste" "F.Mask")
      (net 148 "DSI1_D3_N") (pintype "passive"))
    (pad "95" smd rect (at 8.999 1.54 180) (size 0.2 0.7) (layers "F.Cu" "F.Paste" "F.Mask")
      (net 149 "DSI2_D1_P") (pintype "passive"))
    (pad "96" smd rect (at 8.999 -1.541 180) (size 0.2 0.7) (layers "F.Cu" "F.Paste" "F.Mask")
      (net 150 "DSI1_D3_P") (pintype "passive"))
    (pad "97" smd rect (at 9.4 1.54 180) (size 0.2 0.7) (layers "F.Cu" "F.Paste" "F.Mask")
      (net 11 "GND") (pintype "passive"))
    (pad "98" smd rect (at 9.4 -1.541 180) (size 0.2 0.7) (layers "F.Cu" "F.Paste" "F.Mask")
      (net 11 "GND") (pintype "passive"))
    (pad "99" smd rect (at 9.8 1.54 180) (size 0.2 0.7) (layers "F.Cu" "F.Paste" "F.Mask")
      (net 151 "HDMI0_SDA") (pintype "passive"))
    (pad "100" smd rect (at 9.8 -1.541 180) (size 0.2 0.7) (layers "F.Cu" "F.Paste" "F.Mask")
      (net 152 "HDMI0_SCL") (pintype "passive"))
  )
)
